G04 ================== begin FILE IDENTIFICATION RECORD ==================*
G04 Layout Name:  14629-1a.brd*
G04 Film Name:    L2GND*
G04 File Format:  Gerber RS274X*
G04 File Origin:  Cadence Allegro 16.5-S037*
G04 Origin Date:  Tue Nov 25 11:50:51 2014*
G04 *
G04 Layer:  VIA CLASS/L2GND*
G04 Layer:  PIN/L2GND*
G04 Layer:  ETCH/L2GND*
G04 Layer:  DRAWING FORMAT/LAYER_PCB_STORY*
G04 Layer:  DRAWING FORMAT/LAYER_L2GND*
G04 *
G04 Offset:    (0.00 0.00)*
G04 Mirror:    No*
G04 Mode:      Negative*
G04 Rotation:  0*
G04 FullContactRelief:  No*
G04 UndefLineWidth:     6.00*
G04 ================== end FILE IDENTIFICATION RECORD ====================*
%FSLAX35Y35*MOIN*%
%IR0*IPPOS*OFA0.00000B0.00000*MIA0B0*SFA1.00000B1.00000*%
%AMMACRO19*
4,1,14,.02931,.01517,
.031499,.00985,
.032731,.004231,
.032968,-.001517,
.032204,-.007219,
.030461,-.012702,
.02931,-.01517,
.03299,-.01885,
.035762,-.012835,
.037448,-.00643,
.037995,.00017,
.037388,.006766,
.035646,.013155,
.03299,.01885,
.02931,.01517,
0.0*
4,1,14,.01517,-.02931,
.00985,-.031499,
.004231,-.032731,
-.001517,-.032968,
-.007219,-.032204,
-.012702,-.030461,
-.01517,-.02931,
-.01885,-.03299,
-.012835,-.035762,
-.00643,-.037448,
.00017,-.037995,
.006766,-.037388,
.013155,-.035646,
.01885,-.03299,
.01517,-.02931,
0.0*
4,1,14,-.02931,-.01517,
-.031499,-.00985,
-.032731,-.004231,
-.032968,.001517,
-.032204,.007219,
-.030461,.012702,
-.02931,.01517,
-.03299,.01885,
-.035762,.012835,
-.037448,.00643,
-.037995,-.00017,
-.037388,-.006766,
-.035646,-.013155,
-.03299,-.01885,
-.02931,-.01517,
0.0*
4,1,14,-.01517,.02931,
-.00985,.031499,
-.004231,.032731,
.001517,.032968,
.007219,.032204,
.012702,.030461,
.01517,.02931,
.01885,.03299,
.012835,.035762,
.00643,.037448,
-.00017,.037995,
-.006766,.037388,
-.013155,.035646,
-.01885,.03299,
-.01517,.02931,
0.0*
%
%ADD19MACRO19*%
%AMMACRO17*
4,1,14,.0267,.01255,
.028474,.007723,
.029382,.002661,
.029398,-.002481,
.02852,-.007549,
.026776,-.012386,
.0267,-.01255,
.03042,-.01628,
.032785,-.01075,
.034154,-.004894,
.034484,.001111,
.033768,.007082,
.032025,.012838,
.03042,.01628,
.0267,.01255,
90.*
4,1,14,.01255,-.0267,
.007723,-.028474,
.002661,-.029382,
-.002481,-.029398,
-.007549,-.02852,
-.012386,-.026776,
-.01255,-.0267,
-.01628,-.03042,
-.01075,-.032785,
-.004894,-.034154,
.001111,-.034484,
.007082,-.033768,
.012838,-.032025,
.01628,-.03042,
.01255,-.0267,
90.*
4,1,14,-.0267,-.01255,
-.028474,-.007723,
-.029382,-.002661,
-.029398,.002481,
-.02852,.007549,
-.026776,.012386,
-.0267,.01255,
-.03042,.01628,
-.032785,.01075,
-.034154,.004894,
-.034484,-.001111,
-.033768,-.007082,
-.032025,-.012838,
-.03042,-.01628,
-.0267,-.01255,
90.*
4,1,14,-.01255,.0267,
-.007723,.028474,
-.002661,.029382,
.002481,.029398,
.007549,.02852,
.012386,.026776,
.01255,.0267,
.01628,.03042,
.01075,.032785,
.004894,.034154,
-.001111,.034484,
-.007082,.033768,
-.012838,.032025,
-.01628,.03042,
-.01255,.0267,
90.*
%
%ADD17MACRO17*%
%AMMACRO16*
4,1,16,.07909,.0508,
.08671,.036294,
.091695,.020686,
.093894,.004449,
.09324,-.011923,
.089753,-.027933,
.083539,-.043094,
.07909,-.0508,
.0827,-.05442,
.090894,-.039233,
.096325,-.022853,
.09883,-.005779,
.098332,.01147,
.094847,.028371,
.088479,.04441,
.0827,.05442,
.07909,.0508,
0.0*
4,1,16,.0508,-.07909,
.036294,-.08671,
.020686,-.091695,
.004449,-.093894,
-.011923,-.09324,
-.027933,-.089753,
-.043094,-.083539,
-.0508,-.07909,
-.05442,-.0827,
-.039233,-.090894,
-.022853,-.096325,
-.005779,-.09883,
.01147,-.098332,
.028371,-.094847,
.04441,-.088479,
.05442,-.0827,
.0508,-.07909,
0.0*
4,1,16,-.07909,-.0508,
-.08671,-.036294,
-.091695,-.020686,
-.093894,-.004449,
-.09324,.011923,
-.089753,.027933,
-.083539,.043094,
-.07909,.0508,
-.0827,.05442,
-.090894,.039233,
-.096325,.022853,
-.09883,.005779,
-.098332,-.01147,
-.094847,-.028371,
-.088479,-.04441,
-.0827,-.05442,
-.07909,-.0508,
0.0*
4,1,16,-.0508,.07909,
-.036294,.08671,
-.020686,.091695,
-.004449,.093894,
.011923,.09324,
.027933,.089753,
.043094,.083539,
.0508,.07909,
.05442,.0827,
.039233,.090894,
.022853,.096325,
.005779,.09883,
-.01147,.098332,
-.028371,.094847,
-.04441,.088479,
-.05442,.0827,
-.0508,.07909,
0.0*
%
%ADD16MACRO16*%
%ADD13C,.036*%
%ADD20C,.064*%
%ADD18C,.069*%
%AMMACRO15*
4,1,15,.00398,.00044,
.003999,.000208,
.004004,-.000025,
.003996,-.000258,
.00398,-.00044,
.00483,-.00129,
.004897,-.001007,
.004947,-.000721,
.004981,-.000432,
.004997,-.000141,
.004997,.000149,
.00498,.00044,
.004946,.000729,
.004895,.001015,
.00483,.00129,
.00398,.00044,
90.*
4,1,15,.00044,-.00398,
.000208,-.003999,
-.000025,-.004004,
-.000258,-.003996,
-.00044,-.00398,
-.00129,-.00483,
-.001007,-.004897,
-.000721,-.004947,
-.000432,-.004981,
-.000141,-.004997,
.000149,-.004997,
.00044,-.00498,
.000729,-.004946,
.001015,-.004895,
.00129,-.00483,
.00044,-.00398,
90.*
4,1,15,-.00398,-.00044,
-.003999,-.000208,
-.004004,.000025,
-.003996,.000258,
-.00398,.00044,
-.00483,.00129,
-.004897,.001007,
-.004947,.000721,
-.004981,.000432,
-.004997,.000141,
-.004997,-.000149,
-.00498,-.00044,
-.004946,-.000729,
-.004895,-.001015,
-.00483,-.00129,
-.00398,-.00044,
90.*
4,1,15,-.00044,.00398,
-.000208,.003999,
.000025,.004004,
.000258,.003996,
.00044,.00398,
.00129,.00483,
.001007,.004897,
.000721,.004947,
.000432,.004981,
.000141,.004997,
-.000149,.004997,
-.00044,.00498,
-.000729,.004946,
-.001015,.004895,
-.00129,.00483,
-.00044,.00398,
90.*
%
%ADD15MACRO15*%
%AMMACRO14*
4,1,15,.00398,.00044,
.003999,.000208,
.004004,-.000025,
.003996,-.000258,
.00398,-.00044,
.00483,-.00129,
.004897,-.001007,
.004947,-.000721,
.004981,-.000432,
.004997,-.000141,
.004997,.000149,
.00498,.00044,
.004946,.000729,
.004895,.001015,
.00483,.00129,
.00398,.00044,
0.0*
4,1,15,.00044,-.00398,
.000208,-.003999,
-.000025,-.004004,
-.000258,-.003996,
-.00044,-.00398,
-.00129,-.00483,
-.001007,-.004897,
-.000721,-.004947,
-.000432,-.004981,
-.000141,-.004997,
.000149,-.004997,
.00044,-.00498,
.000729,-.004946,
.001015,-.004895,
.00129,-.00483,
.00044,-.00398,
0.0*
4,1,15,-.00398,-.00044,
-.003999,-.000208,
-.004004,.000025,
-.003996,.000258,
-.00398,.00044,
-.00483,.00129,
-.004897,.001007,
-.004947,.000721,
-.004981,.000432,
-.004997,.000141,
-.004997,-.000149,
-.00498,-.00044,
-.004946,-.000729,
-.004895,-.001015,
-.00483,-.00129,
-.00398,-.00044,
0.0*
4,1,15,-.00044,.00398,
-.000208,.003999,
.000025,.004004,
.000258,.003996,
.00044,.00398,
.00129,.00483,
.001007,.004897,
.000721,.004947,
.000432,.004981,
.000141,.004997,
-.000149,.004997,
-.00044,.00498,
-.000729,.004946,
-.001015,.004895,
-.00129,.00483,
-.00044,.00398,
0.0*
%
%ADD14MACRO14*%
%ADD10C,.114*%
%ADD21C,.186*%
%AMMACRO12*
4,1,15,.00398,.00044,
.003999,.000208,
.004004,-.000025,
.003996,-.000258,
.00398,-.00044,
.00483,-.00129,
.004897,-.001007,
.004947,-.000721,
.004981,-.000432,
.004997,-.000141,
.004997,.000149,
.00498,.00044,
.004946,.000729,
.004895,.001015,
.00483,.00129,
.00398,.00044,
180.*
4,1,15,.00044,-.00398,
.000208,-.003999,
-.000025,-.004004,
-.000258,-.003996,
-.00044,-.00398,
-.00129,-.00483,
-.001007,-.004897,
-.000721,-.004947,
-.000432,-.004981,
-.000141,-.004997,
.000149,-.004997,
.00044,-.00498,
.000729,-.004946,
.001015,-.004895,
.00129,-.00483,
.00044,-.00398,
180.*
4,1,15,-.00398,-.00044,
-.003999,-.000208,
-.004004,.000025,
-.003996,.000258,
-.00398,.00044,
-.00483,.00129,
-.004897,.001007,
-.004947,.000721,
-.004981,.000432,
-.004997,.000141,
-.004997,-.000149,
-.00498,-.00044,
-.004946,-.000729,
-.004895,-.001015,
-.00483,-.00129,
-.00398,-.00044,
180.*
4,1,15,-.00044,.00398,
-.000208,.003999,
.000025,.004004,
.000258,.003996,
.00044,.00398,
.00129,.00483,
.001007,.004897,
.000721,.004947,
.000432,.004981,
.000141,.004997,
-.000149,.004997,
-.00044,.00498,
-.000729,.004946,
-.001015,.004895,
-.00129,.00483,
-.00044,.00398,
180.*
%
%ADD12MACRO12*%
%AMMACRO11*
4,1,16,.07256,.04427,
.079145,.030998,
.083325,.016783,
.084974,.002059,
.08404,-.012728,
.080553,-.027128,
.074619,-.040704,
.07256,-.04427,
.07619,-.04791,
.083352,-.033952,
.087981,-.018962,
.089937,-.003396,
.089161,.012273,
.085675,.027569,
.079586,.042027,
.07619,.04791,
.07256,.04427,
0.0*
4,1,16,.04427,-.07256,
.030998,-.079145,
.016783,-.083325,
.002059,-.084974,
-.012728,-.08404,
-.027128,-.080553,
-.040704,-.074619,
-.04427,-.07256,
-.04791,-.07619,
-.033952,-.083352,
-.018962,-.087981,
-.003396,-.089937,
.012273,-.089161,
.027569,-.085675,
.042027,-.079586,
.04791,-.07619,
.04427,-.07256,
0.0*
4,1,16,-.07256,-.04427,
-.079145,-.030998,
-.083325,-.016783,
-.084974,-.002059,
-.08404,.012728,
-.080553,.027128,
-.074619,.040704,
-.07256,.04427,
-.07619,.04791,
-.083352,.033952,
-.087981,.018962,
-.089937,.003396,
-.089161,-.012273,
-.085675,-.027569,
-.079586,-.042027,
-.07619,-.04791,
-.07256,-.04427,
0.0*
4,1,16,-.04427,.07256,
-.030998,.079145,
-.016783,.083325,
-.002059,.084974,
.012728,.08404,
.027128,.080553,
.040704,.074619,
.04427,.07256,
.04791,.07619,
.033952,.083352,
.018962,.087981,
.003396,.089937,
-.012273,.089161,
-.027569,.085675,
-.042027,.079586,
-.04791,.07619,
-.04427,.07256,
0.0*
%
%ADD11MACRO11*%
%ADD22C,.02*%
%ADD23C,.006*%
%ADD24C,.18204*%
G75*
%LPD*%
G75*
G36*
G01X-43402Y-6000D02*
X646394D01*
Y478441D01*
X-43402D01*
Y-6000D01*
G37*
%LPC*%
G75*
G36*
G01X3004Y468504D02*
G02X3937Y469437I933J0D01*
G01X636457D01*
G02X637390Y468504I0J-933D01*
G01Y388524D01*
G02X636975Y387748I-933J0D01*
G01X627907Y381704D01*
G02X627390Y381547I-518J776D01*
G01X545905D01*
G03X538965Y374607I1J-6941D01*
G01Y357677D01*
G03X545906Y350736I6941J0D01*
G01X627392D01*
G02X627908Y350580I-1J-933D01*
G01X636975Y344536D01*
G02X637390Y343760I-518J-776D01*
G01Y320720D01*
G02X636457Y319787I-933J0D01*
G01X624645D01*
G03X617705Y312847I1J-6941D01*
G01Y135972D01*
G03X624646Y129031I6941J0D01*
G01X636457D01*
G02X637390Y128098I0J-933D01*
G01Y3937D01*
G02X636457Y3004I-933J0D01*
G01X3937D01*
G02X3004Y3937I0J933D01*
G01Y79500D01*
X38086D01*
X55086Y62500D01*
X56000D01*
X547854Y62440D01*
X591000Y105586D01*
Y142086D01*
X609500Y160586D01*
Y195414D01*
X605914Y199000D01*
X566086D01*
X554586Y187500D01*
X417914D01*
X410914Y194500D01*
X-33307Y194440D01*
Y289043D01*
X-1378D01*
G03Y297807I0J4382D01*
G01X-33307D01*
Y362941D01*
X-3937D01*
G03X3004Y369882I0J6941D01*
G01Y468504D01*
G37*
G36*
G01X-33307Y113910D02*
Y192440D01*
X410086Y192500D01*
X417086Y185500D01*
X555414D01*
X566914Y197000D01*
X605086D01*
X607500Y194586D01*
Y161414D01*
X589000Y142914D01*
Y106414D01*
X547026Y64440D01*
X56000Y64500D01*
X55914D01*
X38914Y81500D01*
X3004D01*
Y106969D01*
G03X-3937Y113910I-6941J0D01*
G01X-33307D01*
G37*
%LPD*%
G75*
G36*
G01X25118Y253002D02*
G02X32056Y246063I0J-6938D01*
G01Y226378D01*
G02X25118Y219440I-6938J0D01*
G01X21181D01*
G02X14242Y226378I0J6939D01*
G01Y246063D01*
G02X21181Y253002I6939J0D01*
G01X25118D01*
G37*
G54D24*
X600709Y136909D03*
Y311909D03*
G54D19*
X559489Y427559D03*
X603780Y442126D03*
G54D17*
X570709Y161889D03*
X580709D03*
X570709Y191889D03*
X580709D03*
X570709Y181889D03*
X580709D03*
X570709Y171889D03*
X580709D03*
X570709Y276929D03*
X580709D03*
X570709Y266929D03*
X580709D03*
X570709Y256929D03*
X580709D03*
X570709Y286929D03*
X580709D03*
X590709Y161889D03*
X600709D03*
Y214409D03*
X590709Y204409D03*
Y191889D03*
X600709D03*
X590709Y181889D03*
X600709D03*
X590709Y171889D03*
X600709D03*
X590709Y244409D03*
Y276929D03*
X600709D03*
X590709Y266929D03*
X600709D03*
X590709Y256929D03*
X600709D03*
Y234409D03*
X590709Y224409D03*
Y286929D03*
X600709D03*
G54D16*
X498661Y23622D03*
X518346Y448818D03*
G54D13*
X3398Y326936D03*
X2334Y318654D03*
X1494Y343705D03*
X5694D03*
X10000Y332000D03*
X30923Y335665D03*
X26723D03*
X57398Y348682D03*
X52705Y348626D03*
X48325Y348514D03*
X37500Y386500D03*
X60052Y394674D03*
X55352D03*
X51094Y394478D03*
X520500Y331000D03*
X489500Y375500D03*
X485500D03*
X561500Y232000D03*
X557000Y231500D03*
X543900Y314000D03*
X600000Y337500D03*
Y342000D03*
X595500D03*
Y337500D03*
X612798Y413000D03*
X617798D03*
G54D20*
X571496Y433071D03*
X581339D03*
X591182D03*
G54D18*
X570709Y214409D03*
X580709D03*
X570709Y204409D03*
X580709D03*
X570709Y244409D03*
X580709D03*
X570709Y234409D03*
X580709D03*
X570709Y224409D03*
X580709D03*
X590709Y214409D03*
X600709Y204409D03*
Y244409D03*
X590709Y234409D03*
X600709Y224409D03*
G54D15*
X22000Y387500D03*
X55500Y417000D03*
X512500Y323000D03*
X492000Y321000D03*
X506500Y305500D03*
X520381Y300757D03*
X537136Y326402D03*
X525161Y311000D03*
G54D14*
X25500Y353000D03*
X25000Y343000D03*
X33986Y362933D03*
X22000Y374500D03*
X61898Y358936D03*
X546600Y257971D03*
G54D10*
X-23621Y15748D03*
Y937008D03*
X1312285Y15747D03*
X1312281Y889328D03*
G54D21*
X600709Y136909D03*
Y311909D03*
G54D12*
X6419Y116482D03*
X-3350Y117504D03*
X6419Y126482D03*
X-3581D03*
X6419Y136482D03*
X-3581D03*
X6419Y146482D03*
X-3581D03*
X6419Y156482D03*
X-3581D03*
X-2602Y206936D03*
X7398D03*
X-2602Y216936D03*
X7398D03*
X6419Y166482D03*
X-3581D03*
Y176482D03*
X6419D03*
X-2602Y226936D03*
X7398D03*
X-2602Y246936D03*
X7398D03*
X-2602Y236936D03*
X7398D03*
Y256936D03*
X-2602D03*
Y266936D03*
X7398D03*
Y276936D03*
X-2602D03*
X7398Y286936D03*
X-2948Y302202D03*
X-2602Y316436D03*
X-7102Y327202D03*
X-6940Y316247D03*
X-6602Y347202D03*
X-7102Y337202D03*
X-6602Y357202D03*
X6898Y387436D03*
X6398Y369936D03*
X6898Y445436D03*
Y465436D03*
X16419Y6482D03*
Y26482D03*
X36419Y6482D03*
Y26482D03*
X56419Y46482D03*
X16419Y86482D03*
X36419D03*
X56419Y66482D03*
Y86482D03*
X26419Y116482D03*
X16419D03*
X26419Y126482D03*
X16419D03*
X26419Y136482D03*
X16419D03*
X26419Y146482D03*
X16419D03*
X26419Y156482D03*
X16419D03*
X36419Y126482D03*
X16419Y106482D03*
X36419D03*
Y146482D03*
X56419Y126482D03*
Y106482D03*
Y146482D03*
X27398Y206936D03*
X17398D03*
X27398Y216936D03*
X17398D03*
X26419Y186482D03*
X16419D03*
X26419Y166482D03*
X16419D03*
Y176482D03*
X26419D03*
X36419Y186482D03*
Y166482D03*
X56419Y186482D03*
Y166482D03*
X57398Y206936D03*
X37398D03*
X17398Y256936D03*
X27398D03*
Y266936D03*
X17398D03*
X57398Y226936D03*
X36769D03*
X57398Y246936D03*
Y266936D03*
X36769Y246936D03*
X37398Y266936D03*
X17398Y276936D03*
X27398Y286936D03*
X17398D03*
X27398Y276936D03*
X57398Y286936D03*
X37398D03*
X64398Y304436D03*
X34898Y344936D03*
X62398Y338436D03*
X62000Y442500D03*
X35830Y442464D03*
X19898Y465436D03*
X39898D03*
X76419Y46482D03*
X116419D03*
X96419D03*
X76419Y66482D03*
Y86482D03*
X116419Y66482D03*
X96419D03*
X116419Y86482D03*
X96419D03*
X76419Y126482D03*
Y106482D03*
Y146482D03*
X116419Y126482D03*
Y106482D03*
X96419Y126482D03*
Y106482D03*
X116419Y146482D03*
X96419D03*
X76419Y186482D03*
Y166482D03*
X77398Y206936D03*
X116419Y186482D03*
Y166482D03*
X96419Y186482D03*
Y166482D03*
X117398Y206936D03*
X97398D03*
X77398Y226936D03*
Y246936D03*
Y266936D03*
X117398Y226936D03*
X97398D03*
X117398Y246936D03*
X97398D03*
Y266936D03*
X116398D03*
X77398Y286936D03*
X86398Y303936D03*
X97398Y286936D03*
X116398D03*
X77898Y338436D03*
X78398Y358436D03*
X115330Y337964D03*
X96398Y337936D03*
X115330Y377964D03*
Y357964D03*
X95330Y377964D03*
Y357964D03*
X105330Y442964D03*
X85330D03*
X75500Y417500D03*
X115330Y417964D03*
X95330D03*
X91500Y465500D03*
X117500D03*
X67830Y465464D03*
X136419Y6482D03*
Y46482D03*
X176419Y6482D03*
Y26482D03*
X156419Y6482D03*
Y26482D03*
X176419Y46482D03*
X156419D03*
X136419Y66482D03*
Y86482D03*
X176419Y66482D03*
X156419D03*
X176419Y86482D03*
X156419D03*
X136419Y126482D03*
Y106482D03*
Y146482D03*
X176419Y126482D03*
Y106482D03*
X156419Y126482D03*
Y106482D03*
X176419Y146482D03*
X156419D03*
X136419Y186482D03*
Y166482D03*
X137398Y206936D03*
X176419Y186482D03*
Y166482D03*
X156419Y186482D03*
Y166482D03*
X177398Y206436D03*
X157398Y206936D03*
X137398Y226936D03*
Y246936D03*
Y266936D03*
X177398Y226936D03*
X157398D03*
X177398Y246936D03*
Y266936D03*
X157398Y246936D03*
Y266936D03*
X137398Y286936D03*
X177398D03*
X157398D03*
X135330Y337964D03*
Y377964D03*
Y357964D03*
X175330Y337964D03*
X155330D03*
X175330Y377964D03*
Y357964D03*
X155330Y377964D03*
Y357964D03*
X132000Y442500D03*
X135330Y417964D03*
X175500Y442000D03*
X175330Y417964D03*
X155000Y442000D03*
X155330Y417964D03*
X139898Y465436D03*
X159898D03*
X196419Y6482D03*
Y26482D03*
Y46482D03*
X236419Y6482D03*
Y26482D03*
X216419Y6482D03*
Y26482D03*
X236419Y46482D03*
X216419D03*
X196419Y66482D03*
Y86482D03*
X236419Y66482D03*
X216419D03*
X236419Y86482D03*
X216419D03*
X196419Y126482D03*
Y106482D03*
Y146482D03*
X236419Y126482D03*
Y106482D03*
X216419Y126482D03*
Y106482D03*
X236419Y146482D03*
X216419D03*
X196419Y186482D03*
Y166482D03*
X197398Y206436D03*
X236419Y186482D03*
Y166482D03*
X216419Y186482D03*
Y166482D03*
X217398Y206436D03*
X197398Y226936D03*
Y246936D03*
Y266936D03*
X217398Y226936D03*
Y246936D03*
Y266936D03*
X197398Y286936D03*
X217398D03*
X195330Y337964D03*
Y377964D03*
Y357964D03*
X235330Y337964D03*
X215330D03*
X235330Y377964D03*
Y357964D03*
X215330Y377964D03*
Y357964D03*
X196000Y442500D03*
X195330Y417964D03*
X235830Y442464D03*
X235330Y417964D03*
X215830Y442464D03*
X215330Y417964D03*
X179898Y465436D03*
X219898D03*
X199898D03*
X256419Y6482D03*
Y26482D03*
X276419Y6482D03*
Y26482D03*
X256419Y46482D03*
X276419D03*
X256419Y66482D03*
X273500Y66500D03*
X256419Y86482D03*
X274500Y86500D03*
X256419Y126482D03*
X276419D03*
X256419Y106482D03*
X274500Y106500D03*
X256419Y146482D03*
X276419D03*
X237398Y206436D03*
X256419Y186482D03*
X275500Y186500D03*
X251500Y166500D03*
X276419Y166482D03*
X257398Y206436D03*
X277398D03*
X237398Y226936D03*
Y246936D03*
Y266936D03*
X257398Y226936D03*
X277398D03*
X257398Y246936D03*
X277398D03*
X257398Y266936D03*
X277398D03*
X237398Y286936D03*
X257398D03*
X279398D03*
X255330Y337964D03*
X275330D03*
X255330Y377964D03*
X275330D03*
X255330Y357964D03*
X275330D03*
X255830Y442464D03*
X275830D03*
X255330Y417964D03*
X275330D03*
X239898Y465436D03*
X279898D03*
X259898D03*
X296419Y6482D03*
Y26482D03*
Y46482D03*
X316419Y6482D03*
Y26482D03*
X336419Y6482D03*
Y26482D03*
X316419Y46482D03*
X336419D03*
X302000Y67000D03*
X301000Y86500D03*
X316419Y66482D03*
X336419D03*
X316419Y86482D03*
X336419D03*
X296419Y126482D03*
X300000Y106500D03*
X296419Y146482D03*
X316419Y126482D03*
X336419D03*
X316419Y106482D03*
X336419D03*
X316419Y146482D03*
X336419D03*
X296419Y186482D03*
X295500Y169000D03*
X297398Y206436D03*
X317500Y186500D03*
X336419Y186482D03*
X317000Y166500D03*
X338500Y166000D03*
X317398Y206436D03*
X337398D03*
X297398Y226936D03*
Y246936D03*
Y266936D03*
X317398Y226936D03*
X337398D03*
X317398Y246936D03*
X337398D03*
X317398Y266936D03*
X337398D03*
X300398Y286936D03*
X317398D03*
X337398D03*
X295330Y337964D03*
Y377964D03*
Y357964D03*
X315330Y337964D03*
X335330D03*
X315330Y377964D03*
X335330D03*
X315330Y357964D03*
X335330D03*
X295830Y442464D03*
X295330Y417964D03*
X315830Y442464D03*
X335830D03*
X315330Y417964D03*
X335330D03*
X299898Y465436D03*
X339898D03*
X319898D03*
X356419Y6482D03*
Y26482D03*
Y46482D03*
X376419Y6482D03*
Y26482D03*
X396419Y6482D03*
Y26482D03*
X376419Y46482D03*
X396419D03*
X356419Y66482D03*
Y86482D03*
X376419Y66482D03*
X396419D03*
X376419Y86482D03*
X396419D03*
X356419Y126482D03*
Y106482D03*
Y146482D03*
X376419Y126482D03*
X396419D03*
X376419Y106482D03*
X396419D03*
X376419Y146482D03*
X396419D03*
X357500Y186500D03*
X354500Y166500D03*
X357398Y206436D03*
X376419Y186482D03*
X396419D03*
X380000Y166500D03*
X396419Y166482D03*
X377398Y206436D03*
X397398D03*
X357398Y226936D03*
Y246936D03*
Y266936D03*
X377398Y226936D03*
X397398D03*
X377398Y246936D03*
X397398D03*
X377398Y266936D03*
X397398D03*
X357398Y286936D03*
X377398D03*
X397398D03*
X355330Y337964D03*
Y377964D03*
Y357964D03*
X375330Y337964D03*
X395330D03*
X375330Y377964D03*
X395330D03*
X375330Y357964D03*
X395330D03*
X355830Y442464D03*
X355330Y417964D03*
X375830Y442464D03*
X395830D03*
X375330Y417964D03*
X395330D03*
X399898Y465436D03*
X379898D03*
X359898D03*
X416419Y6482D03*
Y26482D03*
X436419Y6482D03*
X416419Y46482D03*
X436419D03*
X456419D03*
X416419Y66482D03*
X436419D03*
X456419D03*
X416419Y86482D03*
X436419D03*
X456419D03*
X416419Y126482D03*
X436419D03*
X456419D03*
X416419Y106482D03*
X436419D03*
X456419D03*
X416419Y146482D03*
X436419D03*
X456419D03*
X416500Y166000D03*
X417519Y174482D03*
Y170282D03*
X425919D03*
X421719D03*
Y174482D03*
X431100Y174500D03*
Y170300D03*
X439500D03*
Y174500D03*
X435300Y170300D03*
Y174500D03*
X444100D03*
Y170300D03*
X452500D03*
Y174500D03*
X448300Y170300D03*
Y174500D03*
X457100Y175000D03*
Y170800D03*
X461300D03*
Y175000D03*
X418300Y197500D03*
Y201700D03*
X422500D03*
X426700D03*
X422500Y197500D03*
X426700D03*
X431300D03*
Y201700D03*
X435500D03*
X439700D03*
X435500Y197500D03*
X439700D03*
X444800D03*
Y201700D03*
X449000D03*
X453200D03*
X449000Y197500D03*
X453200D03*
X457800D03*
Y201700D03*
X462000D03*
Y197500D03*
X425919Y174482D03*
X436500Y166000D03*
X456500Y166500D03*
X417398Y206436D03*
X437398D03*
X457398D03*
X417398Y226936D03*
X437398D03*
X457398D03*
X417398Y246936D03*
X437398D03*
X457398D03*
X437398Y266936D03*
X457398D03*
X418398D03*
X437398Y286936D03*
X457398D03*
X418398D03*
X415330Y337964D03*
X435398Y338436D03*
X455398D03*
X415330Y377964D03*
Y357964D03*
X435398Y358436D03*
Y378436D03*
X455398Y358436D03*
Y378436D03*
X435830Y442464D03*
X435330Y417964D03*
X455330D03*
X415830Y442464D03*
X415330Y417964D03*
X454500Y465500D03*
X439898Y465436D03*
X419898D03*
X516419Y6482D03*
X476419Y46482D03*
X496419D03*
X516419D03*
Y66482D03*
X476419D03*
X496419D03*
X516419Y86482D03*
X496419D03*
X476419D03*
Y126482D03*
X516419D03*
X496419D03*
X516419Y106482D03*
X496419D03*
X476419D03*
X485443Y160670D03*
X481243D03*
X493843D03*
X489643D03*
X476419Y146482D03*
X516419D03*
X496419D03*
X519221Y160912D03*
X510821D03*
X506621D03*
X515021D03*
X465500Y170800D03*
Y175000D03*
X466200Y201700D03*
Y197500D03*
X485443Y164870D03*
X481243D03*
X493843D03*
X489643D03*
X477284Y174586D03*
X473084D03*
Y170386D03*
X477284D03*
X498395Y174685D03*
Y170485D03*
X492911Y206602D03*
X488711D03*
X492911Y210802D03*
X488711D03*
X484511D03*
Y206602D03*
X480311Y210802D03*
Y206602D03*
X498052Y200389D03*
Y196189D03*
X477087Y201172D03*
X472887D03*
X477087Y196972D03*
X472887D03*
X519221Y165112D03*
X510821D03*
X506621D03*
X515021D03*
X502595Y174685D03*
Y170485D03*
X506135Y210557D03*
X510335D03*
X514535D03*
X518735D03*
X506135Y206357D03*
X510335D03*
X514535D03*
X518735D03*
X502252Y200389D03*
Y196189D03*
X497398Y226936D03*
X477398D03*
X520898Y228436D03*
X497398Y246936D03*
X477398D03*
Y266936D03*
X495398Y338436D03*
X475398D03*
X495398Y358436D03*
Y378436D03*
X475398Y358436D03*
Y378436D03*
X477000Y418000D03*
X499000Y418500D03*
X466500Y428000D03*
X533619Y6482D03*
Y26482D03*
Y46482D03*
X550819Y6482D03*
Y26482D03*
Y46482D03*
X568019Y6482D03*
Y26482D03*
Y46482D03*
X573623Y66967D03*
X536419Y66482D03*
X556419D03*
X536419Y86482D03*
X556419D03*
X576419Y106482D03*
Y126482D03*
X536419D03*
X556419D03*
X536419Y106482D03*
X556419D03*
X544476Y161322D03*
X531876D03*
X536076D03*
X540276D03*
X536419Y146482D03*
X556419D03*
X544477Y210389D03*
X544476Y165522D03*
X536076D03*
X531876D03*
X540276D03*
X552924Y175124D03*
X548724D03*
Y170924D03*
X552924D03*
X527711Y175174D03*
X523511D03*
Y170974D03*
X527711D03*
X531877Y210389D03*
X536077D03*
X540277D03*
X531877Y206189D03*
X536077D03*
X540277D03*
X544477D03*
X527761Y200632D03*
X523561D03*
X527761Y196432D03*
X523561D03*
X553171Y200877D03*
X548971D03*
X553171Y196677D03*
X548971D03*
X540898Y228436D03*
X560500Y268000D03*
X549500Y305500D03*
X559996Y282972D03*
X561500Y298000D03*
X534000Y282000D03*
X577500Y305000D03*
X548000Y442500D03*
X553000Y425000D03*
X568500Y464841D03*
X538000D03*
X634119Y26482D03*
X585219Y46482D03*
Y26482D03*
Y6482D03*
X602419Y26482D03*
Y6482D03*
X619619D03*
Y26482D03*
Y46482D03*
X634119D03*
Y6482D03*
X602419Y46482D03*
X628500Y104000D03*
X626500Y78500D03*
X611253Y65701D03*
X584543Y86671D03*
X611398Y86936D03*
X633753Y65701D03*
X633898Y86936D03*
X634000Y123500D03*
X607000D03*
X616000Y138000D03*
Y115500D03*
X594500Y117000D03*
X616000Y173500D03*
X615500Y199000D03*
X615898Y244436D03*
Y224436D03*
X615398Y266436D03*
X587500Y318500D03*
X600000Y298500D03*
X616498Y316236D03*
X615398Y284436D03*
X633398Y325436D03*
X630000Y345500D03*
Y387500D03*
X610898Y425436D03*
Y445436D03*
X632898Y404936D03*
Y444936D03*
Y424936D03*
X592000Y464841D03*
X610898Y465436D03*
X632898Y464936D03*
G54D11*
X30157Y61023D03*
Y415354D03*
%LPC*%
G75*
G54D22*
G01X-4246Y-109426D02*
Y-189426D01*
G01D02*
X1290354D01*
G01X-4246Y-144926D02*
X1290354D01*
G01X-8246Y-93426D02*
G02I-12000J0D01*
G01X-13396D02*
G02I-6850J0D01*
G01X-20246Y-109426D02*
Y-77426D01*
G01X-4246Y-93426D02*
X-36246D01*
G01X-4246Y-109426D02*
X1290354D01*
G01X502854D02*
Y-189426D01*
G01X640354Y-109426D02*
Y-189426D01*
G01X755354Y-109426D02*
Y-189426D01*
G01X922854Y-109426D02*
Y-189426D01*
G01X1092854Y-109426D02*
Y-189426D01*
G01X1290354Y-109426D02*
Y-189426D01*
G01X1318354Y-93426D02*
G02I-12000J0D01*
G01X1313204D02*
G02I-6850J0D01*
G01X1306354Y-109426D02*
Y-77426D01*
G01X1322354Y-93426D02*
X1290354D01*
G54D23*
G01X121969Y-179426D02*
Y-161926D01*
G01X131139D02*
Y-179426D01*
G01Y-170676D02*
X121969D01*
G01X144054Y-179426D02*
X142744Y-179134D01*
X141434Y-177968D01*
X140560Y-175926D01*
X140124Y-173593D01*
X140560Y-171259D01*
X141434Y-169218D01*
X142744Y-168051D01*
X144054Y-167760D01*
X145364Y-168051D01*
X146674Y-169218D01*
X147547Y-171259D01*
X147766Y-173593D01*
X147547Y-175926D01*
X146674Y-177968D01*
X145364Y-179134D01*
X144054Y-179426D01*
G01X157842D02*
Y-167760D01*
G01Y-170676D02*
X158716Y-169218D01*
X160026Y-168051D01*
X161772Y-167760D01*
X163300Y-168051D01*
X164611Y-169218D01*
X165266Y-171259D01*
Y-179426D01*
G01X175779Y-171551D02*
X182766D01*
X182111Y-169509D01*
X181019Y-168343D01*
X179491Y-167760D01*
X177962Y-168051D01*
X176652Y-168926D01*
X175779Y-170968D01*
X175342Y-172718D01*
Y-174468D01*
X175779Y-176218D01*
X176871Y-177968D01*
X178181Y-179134D01*
X179709Y-179426D01*
X181237Y-178843D01*
X182766Y-177093D01*
G01X191969Y-184676D02*
X193279Y-185259D01*
X195026Y-184676D01*
X196117Y-183510D01*
X196991Y-182051D01*
X198300Y-177385D01*
X201139Y-167760D01*
G01X194152D02*
X198300Y-177385D01*
G01X233300Y-170093D02*
X234174Y-169218D01*
X234829Y-167760D01*
X235266Y-165717D01*
X234829Y-163968D01*
X233956Y-162801D01*
X232427Y-161926D01*
X226532D01*
Y-179426D01*
X233737D01*
X235266Y-178260D01*
X236139Y-176509D01*
X236576Y-174468D01*
X236139Y-172426D01*
X234829Y-170676D01*
X233300Y-170093D01*
X226532D01*
G01X252984Y-179426D02*
Y-167760D01*
G01Y-169801D02*
X252111Y-168635D01*
X250800Y-168051D01*
X249272Y-167760D01*
X247744Y-168343D01*
X246434Y-169509D01*
X245560Y-171259D01*
X245124Y-173593D01*
X245560Y-175926D01*
X246434Y-177676D01*
X247744Y-178843D01*
X249272Y-179426D01*
X250800Y-179134D01*
X252111Y-178260D01*
X252984Y-177093D01*
G01X270484Y-161926D02*
Y-179426D01*
G01Y-176802D02*
X269611Y-178260D01*
X268300Y-179134D01*
X266772Y-179426D01*
X265026Y-178843D01*
X263716Y-177385D01*
X262842Y-175635D01*
X262624Y-173593D01*
X262842Y-171551D01*
X263716Y-169801D01*
X265026Y-168343D01*
X266772Y-167760D01*
X268300Y-168051D01*
X269392Y-168635D01*
X270484Y-169801D01*
G01X280997Y-183801D02*
X282526Y-184968D01*
X284272Y-185259D01*
X285800Y-184968D01*
X287111Y-183510D01*
X287984Y-181468D01*
Y-167760D01*
G01Y-170093D02*
X287111Y-168926D01*
X285800Y-168051D01*
X284272Y-167760D01*
X282526Y-168343D01*
X281434Y-169509D01*
X280560Y-171551D01*
X280124Y-173593D01*
X280342Y-175343D01*
X281216Y-177385D01*
X282526Y-178843D01*
X284272Y-179426D01*
X285582Y-179134D01*
X287111Y-177968D01*
X287984Y-176802D01*
G01X298279Y-171551D02*
X305266D01*
X304611Y-169509D01*
X303519Y-168343D01*
X301991Y-167760D01*
X300462Y-168051D01*
X299152Y-168926D01*
X298279Y-170968D01*
X297842Y-172718D01*
Y-174468D01*
X298279Y-176218D01*
X299371Y-177968D01*
X300681Y-179134D01*
X302209Y-179426D01*
X303737Y-178843D01*
X305266Y-177093D01*
G01X315997Y-179426D02*
Y-167760D01*
G01Y-170093D02*
X317089Y-168926D01*
X318181Y-168051D01*
X319709Y-167760D01*
X320800Y-168051D01*
X322111Y-168926D01*
G01X349687Y-179426D02*
Y-161926D01*
X354927D01*
X356674Y-162801D01*
X357984Y-164843D01*
X358421Y-167176D01*
X357984Y-169509D01*
X356892Y-171259D01*
X354927Y-172135D01*
X349687D01*
G01X371554Y-161926D02*
Y-179426D01*
G01X366532Y-161926D02*
X376576D01*
G01X390800Y-170093D02*
X391674Y-169218D01*
X392329Y-167760D01*
X392766Y-165717D01*
X392329Y-163968D01*
X391456Y-162801D01*
X389927Y-161926D01*
X384032D01*
Y-179426D01*
X391237D01*
X392766Y-178260D01*
X393639Y-176509D01*
X394076Y-174468D01*
X393639Y-172426D01*
X392329Y-170676D01*
X390800Y-170093D01*
X384032D01*
G01X208377Y-134426D02*
Y-116926D01*
X214054Y-131509D01*
X219731Y-116926D01*
Y-134426D01*
G01X231554D02*
X230244Y-134134D01*
X228934Y-132968D01*
X228060Y-130926D01*
X227624Y-128593D01*
X228060Y-126259D01*
X228934Y-124218D01*
X230244Y-123051D01*
X231554Y-122760D01*
X232864Y-123051D01*
X234174Y-124218D01*
X235047Y-126259D01*
X235266Y-128593D01*
X235047Y-130926D01*
X234174Y-132968D01*
X232864Y-134134D01*
X231554Y-134426D01*
G01X252984Y-116926D02*
Y-134426D01*
G01Y-131802D02*
X252111Y-133260D01*
X250800Y-134134D01*
X249272Y-134426D01*
X247526Y-133843D01*
X246216Y-132385D01*
X245342Y-130635D01*
X245124Y-128593D01*
X245342Y-126551D01*
X246216Y-124801D01*
X247526Y-123343D01*
X249272Y-122760D01*
X250800Y-123051D01*
X251892Y-123635D01*
X252984Y-124801D01*
G01X263279Y-126551D02*
X270266D01*
X269611Y-124509D01*
X268519Y-123343D01*
X266991Y-122760D01*
X265462Y-123051D01*
X264152Y-123926D01*
X263279Y-125968D01*
X262842Y-127718D01*
Y-129468D01*
X263279Y-131218D01*
X264371Y-132968D01*
X265681Y-134134D01*
X267209Y-134426D01*
X268737Y-133843D01*
X270266Y-132093D01*
G01X284054Y-134426D02*
Y-116926D01*
G01X536554Y-179426D02*
Y-161926D01*
X533934Y-165426D01*
G01Y-179426D02*
X539174D01*
G01X556674D02*
Y-161926D01*
X548595Y-174468D01*
X559513D01*
G01X567406Y-172135D02*
X568934Y-170093D01*
X570244Y-168926D01*
X571991Y-168343D01*
X573519Y-168926D01*
X574611Y-170093D01*
X575484Y-171843D01*
X575702Y-173884D01*
X575484Y-175635D01*
X574611Y-177385D01*
X573300Y-178843D01*
X571772Y-179426D01*
X570026Y-178843D01*
X568497Y-177093D01*
X567624Y-174468D01*
X567406Y-171551D01*
X567842Y-167760D01*
X568497Y-165717D01*
X569589Y-163676D01*
X571117Y-162218D01*
X572646Y-161926D01*
X574174Y-162509D01*
X575266Y-163968D01*
G01X584906Y-164843D02*
X586216Y-163093D01*
X587744Y-162218D01*
X589491Y-161926D01*
X591674Y-162509D01*
X593202Y-163968D01*
X593639Y-165717D01*
X593421Y-167468D01*
X592547Y-168926D01*
X588181Y-171843D01*
X586216Y-173884D01*
X584906Y-176802D01*
X584469Y-179426D01*
X593639D01*
G01X602842Y-177385D02*
X604371Y-178843D01*
X606117Y-179426D01*
X607864Y-178843D01*
X609392Y-177093D01*
X610484Y-174468D01*
X610921Y-171843D01*
Y-168635D01*
X610484Y-166010D01*
X609392Y-163676D01*
X608082Y-162509D01*
X606554Y-161926D01*
X604807Y-162509D01*
X603497Y-163676D01*
X602624Y-165426D01*
X602187Y-167760D01*
X602624Y-169801D01*
X603716Y-171843D01*
X605026Y-173010D01*
X606554Y-173301D01*
X608300Y-172718D01*
X609611Y-171259D01*
X610921Y-168635D01*
G01X523437Y-134426D02*
Y-116926D01*
X528677D01*
X530424Y-117801D01*
X531734Y-119843D01*
X532171Y-122176D01*
X531734Y-124509D01*
X530642Y-126259D01*
X528677Y-127135D01*
X523437D01*
G01X550107Y-118385D02*
X548797Y-117509D01*
X547269Y-116926D01*
X545522D01*
X543557Y-117801D01*
X542029Y-119259D01*
X540937Y-121010D01*
X540064Y-123926D01*
X539845Y-126551D01*
X540282Y-129176D01*
X540937Y-130926D01*
X542247Y-132676D01*
X543776Y-133843D01*
X545304Y-134426D01*
X546832D01*
X548361Y-133843D01*
X549671Y-132968D01*
X550763Y-131802D01*
G01X564550Y-125093D02*
X565424Y-124218D01*
X566079Y-122760D01*
X566516Y-120717D01*
X566079Y-118968D01*
X565206Y-117801D01*
X563677Y-116926D01*
X557782D01*
Y-134426D01*
X564987D01*
X566516Y-133260D01*
X567389Y-131509D01*
X567826Y-129468D01*
X567389Y-127426D01*
X566079Y-125676D01*
X564550Y-125093D01*
X557782D01*
G01X573754Y-140259D02*
X586854D01*
G01X592782Y-134426D02*
Y-116926D01*
X602826Y-134426D01*
Y-116926D01*
G01X615304Y-134426D02*
X613557Y-134134D01*
X612029Y-132968D01*
X610719Y-131218D01*
X609845Y-129176D01*
X609409Y-126843D01*
Y-124509D01*
X609845Y-122176D01*
X610719Y-120134D01*
X612029Y-118385D01*
X613557Y-117218D01*
X615304Y-116926D01*
X617050Y-117218D01*
X618579Y-118385D01*
X619889Y-120134D01*
X620763Y-122176D01*
X621199Y-124509D01*
Y-126843D01*
X620763Y-129176D01*
X619889Y-131218D01*
X618579Y-132968D01*
X617050Y-134134D01*
X615304Y-134426D01*
G01X689104Y-179426D02*
Y-161926D01*
X686484Y-165426D01*
G01Y-179426D02*
X691724D01*
G01X701145D02*
X706604Y-161926D01*
X712063Y-179426D01*
G01X710097Y-173301D02*
X703110D01*
G01X666145Y-116926D02*
X671604Y-134426D01*
X677063Y-116926D01*
G01X693471Y-134426D02*
X684737D01*
Y-116926D01*
X693471D01*
G01X689977Y-125384D02*
X684737D01*
G01X702237Y-134426D02*
Y-116926D01*
X707696D01*
X709442Y-117801D01*
X710534Y-118968D01*
X710971Y-121301D01*
X710534Y-123635D01*
X709224Y-125093D01*
X707696Y-125968D01*
X702237D01*
G01X707696D02*
X710971Y-134426D01*
G01X724104Y-135009D02*
X723667Y-134718D01*
Y-134134D01*
X724104Y-133843D01*
X724541Y-134134D01*
Y-134718D01*
X724104Y-135009D01*
G01X799687Y-161926D02*
Y-179426D01*
X808421D01*
G01X817406Y-164843D02*
X818716Y-163093D01*
X820244Y-162218D01*
X821991Y-161926D01*
X824174Y-162509D01*
X825702Y-163968D01*
X826139Y-165717D01*
X825921Y-167468D01*
X825047Y-168926D01*
X820681Y-171843D01*
X818716Y-173884D01*
X817406Y-176802D01*
X816969Y-179426D01*
X826139D01*
G01X840364Y-170676D02*
X844731D01*
Y-175926D01*
X843421Y-177676D01*
X841892Y-178843D01*
X839709Y-179426D01*
X837526Y-178843D01*
X835997Y-177676D01*
X834687Y-175926D01*
X833814Y-173884D01*
X833377Y-171551D01*
Y-169509D01*
X833814Y-167760D01*
X834687Y-165717D01*
X835997Y-163968D01*
X837307Y-162801D01*
X839054Y-161926D01*
X840582D01*
X842329Y-162509D01*
X843639Y-163676D01*
G01X851532Y-179426D02*
Y-161926D01*
X861576Y-179426D01*
Y-161926D01*
G01X869251Y-179426D02*
Y-161926D01*
X873617D01*
X875364Y-162801D01*
X876674Y-163968D01*
X877766Y-165717D01*
X878639Y-167760D01*
X878857Y-170676D01*
X878639Y-173593D01*
X877766Y-175635D01*
X876674Y-177385D01*
X875364Y-178551D01*
X873617Y-179426D01*
X869251D01*
G01X790937Y-116926D02*
Y-134426D01*
X799671D01*
G01X816734D02*
Y-122760D01*
G01Y-124801D02*
X815861Y-123635D01*
X814550Y-123051D01*
X813022Y-122760D01*
X811494Y-123343D01*
X810184Y-124509D01*
X809310Y-126259D01*
X808874Y-128593D01*
X809310Y-130926D01*
X810184Y-132676D01*
X811494Y-133843D01*
X813022Y-134426D01*
X814550Y-134134D01*
X815861Y-133260D01*
X816734Y-132093D01*
G01X825719Y-139676D02*
X827029Y-140259D01*
X828776Y-139676D01*
X829867Y-138510D01*
X830741Y-137051D01*
X832050Y-132385D01*
X834889Y-122760D01*
G01X827902D02*
X832050Y-132385D01*
G01X844529Y-126551D02*
X851516D01*
X850861Y-124509D01*
X849769Y-123343D01*
X848241Y-122760D01*
X846712Y-123051D01*
X845402Y-123926D01*
X844529Y-125968D01*
X844092Y-127718D01*
Y-129468D01*
X844529Y-131218D01*
X845621Y-132968D01*
X846931Y-134134D01*
X848459Y-134426D01*
X849987Y-133843D01*
X851516Y-132093D01*
G01X862247Y-134426D02*
Y-122760D01*
G01Y-125093D02*
X863339Y-123926D01*
X864431Y-123051D01*
X865959Y-122760D01*
X867050Y-123051D01*
X868361Y-123926D01*
G01X879529Y-132385D02*
X880621Y-133551D01*
X882149Y-134426D01*
X883459D01*
X884769Y-133843D01*
X885642Y-132968D01*
X886079Y-131802D01*
X885861Y-130051D01*
X884987Y-129176D01*
X881057Y-127426D01*
X880184Y-125384D01*
X880621Y-123926D01*
X881494Y-123051D01*
X882804Y-122760D01*
X884114Y-123051D01*
X885424Y-123926D01*
G01X924737Y-175926D02*
X925829Y-177676D01*
X927139Y-178843D01*
X928667Y-179426D01*
X930414Y-178843D01*
X931724Y-177676D01*
X933034Y-175926D01*
X933471Y-173593D01*
Y-161926D01*
G01X946604Y-179426D02*
X944857Y-179134D01*
X943329Y-177968D01*
X942019Y-176218D01*
X941145Y-174176D01*
X940709Y-171843D01*
Y-169509D01*
X941145Y-167176D01*
X942019Y-165134D01*
X943329Y-163385D01*
X944857Y-162218D01*
X946604Y-161926D01*
X948350Y-162218D01*
X949879Y-163385D01*
X951189Y-165134D01*
X952063Y-167176D01*
X952499Y-169509D01*
Y-171843D01*
X952063Y-174176D01*
X951189Y-176218D01*
X949879Y-177968D01*
X948350Y-179134D01*
X946604Y-179426D01*
G01X959519Y-177093D02*
X961266Y-178551D01*
X963231Y-179426D01*
X964977D01*
X966724Y-178551D01*
X968034Y-177093D01*
X968689Y-175051D01*
X968252Y-173010D01*
X967161Y-171259D01*
X965196Y-170093D01*
X962576Y-169509D01*
X961047Y-168343D01*
X960392Y-166301D01*
X960829Y-164259D01*
X961921Y-162801D01*
X963449Y-161926D01*
X964977D01*
X966506Y-162509D01*
X967816Y-163968D01*
G01X985971Y-179426D02*
X977237D01*
Y-161926D01*
X985971D01*
G01X982477Y-170384D02*
X977237D01*
G01X994737Y-179426D02*
Y-161926D01*
X999977D01*
X1001724Y-162801D01*
X1003034Y-164843D01*
X1003471Y-167176D01*
X1003034Y-169509D01*
X1001942Y-171259D01*
X999977Y-172135D01*
X994737D01*
G01X1012019Y-179426D02*
Y-161926D01*
G01X1021189D02*
Y-179426D01*
G01Y-170676D02*
X1012019D01*
G01X1047237Y-161926D02*
Y-179426D01*
X1055971D01*
G01X1063645D02*
X1069104Y-161926D01*
X1074563Y-179426D01*
G01X1072597Y-173301D02*
X1065610D01*
G01X1081801Y-161926D02*
Y-174468D01*
X1082674Y-177093D01*
X1084421Y-178843D01*
X1086604Y-179426D01*
X1088787Y-178843D01*
X1090534Y-177093D01*
X1091407Y-174468D01*
Y-161926D01*
G01X941801Y-134426D02*
Y-116926D01*
X946167D01*
X947914Y-117801D01*
X949224Y-118968D01*
X950316Y-120717D01*
X951189Y-122760D01*
X951407Y-125676D01*
X951189Y-128593D01*
X950316Y-130635D01*
X949224Y-132385D01*
X947914Y-133551D01*
X946167Y-134426D01*
X941801D01*
G01X960829Y-126551D02*
X967816D01*
X967161Y-124509D01*
X966069Y-123343D01*
X964541Y-122760D01*
X963012Y-123051D01*
X961702Y-123926D01*
X960829Y-125968D01*
X960392Y-127718D01*
Y-129468D01*
X960829Y-131218D01*
X961921Y-132968D01*
X963231Y-134134D01*
X964759Y-134426D01*
X966287Y-133843D01*
X967816Y-132093D01*
G01X978329Y-132385D02*
X979421Y-133551D01*
X980949Y-134426D01*
X982259D01*
X983569Y-133843D01*
X984442Y-132968D01*
X984879Y-131802D01*
X984661Y-130051D01*
X983787Y-129176D01*
X979857Y-127426D01*
X978984Y-125384D01*
X979421Y-123926D01*
X980294Y-123051D01*
X981604Y-122760D01*
X982914Y-123051D01*
X984224Y-123926D01*
G01X999104Y-122760D02*
Y-134426D01*
G01Y-118093D02*
X998667Y-117801D01*
Y-117218D01*
X999104Y-116926D01*
X999541Y-117218D01*
Y-117801D01*
X999104Y-118093D01*
G01X1013547Y-138801D02*
X1015076Y-139968D01*
X1016822Y-140259D01*
X1018350Y-139968D01*
X1019661Y-138510D01*
X1020534Y-136468D01*
Y-122760D01*
G01Y-125093D02*
X1019661Y-123926D01*
X1018350Y-123051D01*
X1016822Y-122760D01*
X1015076Y-123343D01*
X1013984Y-124509D01*
X1013110Y-126551D01*
X1012674Y-128593D01*
X1012892Y-130343D01*
X1013766Y-132385D01*
X1015076Y-133843D01*
X1016822Y-134426D01*
X1018132Y-134134D01*
X1019661Y-132968D01*
X1020534Y-131802D01*
G01X1030392Y-134426D02*
Y-122760D01*
G01Y-125676D02*
X1031266Y-124218D01*
X1032576Y-123051D01*
X1034322Y-122760D01*
X1035850Y-123051D01*
X1037161Y-124218D01*
X1037816Y-126259D01*
Y-134426D01*
G01X1048329Y-126551D02*
X1055316D01*
X1054661Y-124509D01*
X1053569Y-123343D01*
X1052041Y-122760D01*
X1050512Y-123051D01*
X1049202Y-123926D01*
X1048329Y-125968D01*
X1047892Y-127718D01*
Y-129468D01*
X1048329Y-131218D01*
X1049421Y-132968D01*
X1050731Y-134134D01*
X1052259Y-134426D01*
X1053787Y-133843D01*
X1055316Y-132093D01*
G01X1066047Y-134426D02*
Y-122760D01*
G01Y-125093D02*
X1067139Y-123926D01*
X1068231Y-123051D01*
X1069759Y-122760D01*
X1070850Y-123051D01*
X1072161Y-123926D01*
G01X1112804Y-179426D02*
Y-161926D01*
X1110184Y-165426D01*
G01Y-179426D02*
X1115424D01*
G01X1130304D02*
Y-161926D01*
X1127684Y-165426D01*
G01Y-179426D02*
X1132924D01*
G01X1143874Y-180009D02*
X1151734Y-161926D01*
G01X1161156Y-164843D02*
X1162466Y-163093D01*
X1163994Y-162218D01*
X1165741Y-161926D01*
X1167924Y-162509D01*
X1169452Y-163968D01*
X1169889Y-165717D01*
X1169671Y-167468D01*
X1168797Y-168926D01*
X1164431Y-171843D01*
X1162466Y-173884D01*
X1161156Y-176802D01*
X1160719Y-179426D01*
X1169889D01*
G01X1178001Y-176802D02*
X1179310Y-178260D01*
X1180839Y-179134D01*
X1182804Y-179426D01*
X1184769Y-178843D01*
X1186297Y-177676D01*
X1187389Y-175635D01*
X1187607Y-173301D01*
X1187171Y-170968D01*
X1186079Y-169509D01*
X1184550Y-168343D01*
X1183022Y-168051D01*
X1181494Y-168343D01*
X1179529Y-169509D01*
X1180184Y-161926D01*
X1186079D01*
G01X1196374Y-180009D02*
X1204234Y-161926D01*
G01X1213656Y-164843D02*
X1214966Y-163093D01*
X1216494Y-162218D01*
X1218241Y-161926D01*
X1220424Y-162509D01*
X1221952Y-163968D01*
X1222389Y-165717D01*
X1222171Y-167468D01*
X1221297Y-168926D01*
X1216931Y-171843D01*
X1214966Y-173884D01*
X1213656Y-176802D01*
X1213219Y-179426D01*
X1222389D01*
G01X1235304Y-161926D02*
X1233557Y-162509D01*
X1232247Y-163968D01*
X1231374Y-165717D01*
X1230719Y-168051D01*
X1230501Y-170676D01*
X1230719Y-173301D01*
X1231374Y-175635D01*
X1232247Y-177385D01*
X1233557Y-178843D01*
X1235304Y-179426D01*
X1237050Y-178843D01*
X1238361Y-177385D01*
X1239234Y-175635D01*
X1239889Y-173301D01*
X1240107Y-170676D01*
X1239889Y-168051D01*
X1239234Y-165717D01*
X1238361Y-163968D01*
X1237050Y-162509D01*
X1235304Y-161926D01*
G01X1252804Y-179426D02*
Y-161926D01*
X1250184Y-165426D01*
G01Y-179426D02*
X1255424D01*
G01X1272924D02*
Y-161926D01*
X1264845Y-174468D01*
X1275763D01*
G01X1160501Y-134426D02*
Y-116926D01*
X1164867D01*
X1166614Y-117801D01*
X1167924Y-118968D01*
X1169016Y-120717D01*
X1169889Y-122760D01*
X1170107Y-125676D01*
X1169889Y-128593D01*
X1169016Y-130635D01*
X1167924Y-132385D01*
X1166614Y-133551D01*
X1164867Y-134426D01*
X1160501D01*
G01X1186734D02*
Y-122760D01*
G01Y-124801D02*
X1185861Y-123635D01*
X1184550Y-123051D01*
X1183022Y-122760D01*
X1181494Y-123343D01*
X1180184Y-124509D01*
X1179310Y-126259D01*
X1178874Y-128593D01*
X1179310Y-130926D01*
X1180184Y-132676D01*
X1181494Y-133843D01*
X1183022Y-134426D01*
X1184550Y-134134D01*
X1185861Y-133260D01*
X1186734Y-132093D01*
G01X1200304Y-116926D02*
Y-134426D01*
G01X1197247Y-122760D02*
X1203361D01*
G01X1214529Y-126551D02*
X1221516D01*
X1220861Y-124509D01*
X1219769Y-123343D01*
X1218241Y-122760D01*
X1216712Y-123051D01*
X1215402Y-123926D01*
X1214529Y-125968D01*
X1214092Y-127718D01*
Y-129468D01*
X1214529Y-131218D01*
X1215621Y-132968D01*
X1216931Y-134134D01*
X1218459Y-134426D01*
X1219987Y-133843D01*
X1221516Y-132093D01*
M02*
